# SCM (Grand Teton) — schematic netlist excerpt (pin names and nets, part order shuffled) for the footprints in the layout excerpt that follows; sources: Cadence DE-HDL packaged netlist, KiCad conversion of 12092022_DA0F0TMDCD0_F0T_Management_Board_D_brd_V3_OCP.brd

R571  Q_RES  0 5% CHIP  pkg 0402LF  page 34 : A = IRQ_BMC_PCH_NMI_N ; B = IRQ_BMC_PCH_NMI_R_N
R134  Q_RES  0 5% CHIP  pkg 0402LF  page 36 : A = FM_BMC_UARTSW_LSB_N ; B = FM_UARTSW_LSB_N

(kicad_pcb
	(version 20260206)
	(generator "pcbnew")
	(generator_version "10.0")
	(general
		(thickness 1.6)
		(legacy_teardrops no)
	)
	(paper "A4")
	(title_block
		(title "12092022_DA0F0TMDCD0_F0T_Management_Board_D_brd_V3_OCP.brd")
		(comment 1 "Grand Teton / footprints 1053-1054 of 1440")
	)
	(layers
		(0 "F.Cu" signal "TOP")
		(4 "In1.Cu" signal "GND")
		(6 "In2.Cu" signal "IN1")
		(8 "In3.Cu" signal "GND1")
		(10 "In4.Cu" signal "IN2")
		(12 "In5.Cu" signal "VCC")
		(14 "In6.Cu" signal "VCC1")
		(16 "In7.Cu" signal "IN3")
		(18 "In8.Cu" signal "GND2")
		(20 "In9.Cu" signal "IN4")
		(22 "In10.Cu" signal "GND3")
		(2 "B.Cu" signal "BOTTOM")
		(9 "F.Adhes" user "F.Adhesive")
		(11 "B.Adhes" user "B.Adhesive")
		(13 "F.Paste" user "Package Geometry/Pastemask Top")
		(15 "B.Paste" user "Package Geometry/Pastemask Bottom")
		(5 "F.SilkS" user "Ref Des/Silkscreen Top")
		(7 "B.SilkS" user "Ref Des/Silkscreen Bottom")
		(1 "F.Mask" user "Board Geometry/Soldermask Top")
		(3 "B.Mask" user "Board Geometry/Soldermask Bottom")
		(17 "Dwgs.User" user "User.Drawings")
		(19 "Cmts.User" user "User.Comments")
		(21 "Eco1.User" user "User.Eco1")
		(23 "Eco2.User" user "User.Eco2")
		(25 "Edge.Cuts" user "Board Geometry/Outline")
		(27 "Margin" user)
		(31 "F.CrtYd" user "Package Geometry/Place Bound Top")
		(29 "B.CrtYd" user "Package Geometry/Place Bound Bottom")
		(35 "F.Fab" user "Ref Des/Assembly Top")
		(33 "B.Fab" user "Ref Des/Assembly Bottom")
	)
	(footprint ""
		(layer "B.Cu")
		(at 19.431 -83.693 -90)
		(property "Reference" "R571"
			(at 0 0 90)
			(layer "B.SilkS")
			(hide yes)
			(effects
				(font
					(size 1.27 1.27)
				)
				(justify mirror)
			)
		)
		(property "Value" ""
			(at 0 0 90)
			(layer "B.Fab")
			(effects
				(font
					(size 1.27 1.27)
				)
				(justify mirror)
			)
		)
		(duplicate_pad_numbers_are_jumpers no)
		(fp_line
			(start -0.7874 0.4064)
			(end 0.7874 0.4064)
			(stroke
				(width 0.1524)
				(type default)
			)
			(layer "B.SilkS")
		)
		(fp_line
			(start 0.7874 0.4064)
			(end 0.7874 -0.4064)
			(stroke
				(width 0.1524)
				(type default)
			)
			(layer "B.SilkS")
		)
		(fp_line
			(start -0.7874 -0.4064)
			(end -0.7874 0.4064)
			(stroke
				(width 0.1524)
				(type default)
			)
			(layer "B.SilkS")
		)
		(fp_line
			(start 0.7874 -0.4064)
			(end -0.7874 -0.4064)
			(stroke
				(width 0.1524)
				(type default)
			)
			(layer "B.SilkS")
		)
		(fp_line
			(start -0.67945 0.3048)
			(end -0.120396 0.3048)
			(stroke
				(width 0.1)
				(type default)
			)
			(layer "B.Fab")
		)
		(fp_line
			(start -0.120396 0.3048)
			(end -0.120396 0.2794)
			(stroke
				(width 0.1)
				(type default)
			)
			(layer "B.Fab")
		)
		(fp_line
			(start 0.12065 0.3048)
			(end 0.67945 0.3048)
			(stroke
				(width 0.1)
				(type default)
			)
			(layer "B.Fab")
		)
		(fp_line
			(start 0.67945 0.3048)
			(end 0.67945 -0.305054)
			(stroke
				(width 0.1)
				(type default)
			)
			(layer "B.Fab")
		)
		(fp_line
			(start -0.120396 0.2794)
			(end 0.12065 0.2794)
			(stroke
				(width 0.1)
				(type default)
			)
			(layer "B.Fab")
		)
		(fp_line
			(start 0.12065 0.2794)
			(end 0.12065 0.3048)
			(stroke
				(width 0.1)
				(type default)
			)
			(layer "B.Fab")
		)
		(fp_line
			(start -0.12065 -0.2794)
			(end -0.12065 -0.3048)
			(stroke
				(width 0.1)
				(type default)
			)
			(layer "B.Fab")
		)
		(fp_line
			(start 0.12065 -0.2794)
			(end -0.12065 -0.2794)
			(stroke
				(width 0.1)
				(type default)
			)
			(layer "B.Fab")
		)
		(fp_line
			(start -0.67945 -0.3048)
			(end -0.67945 0.3048)
			(stroke
				(width 0.1)
				(type default)
			)
			(layer "B.Fab")
		)
		(fp_line
			(start -0.12065 -0.3048)
			(end -0.67945 -0.3048)
			(stroke
				(width 0.1)
				(type default)
			)
			(layer "B.Fab")
		)
		(fp_line
			(start 0.12065 -0.305054)
			(end 0.12065 -0.2794)
			(stroke
				(width 0.1)
				(type default)
			)
			(layer "B.Fab")
		)
		(fp_line
			(start 0.67945 -0.305054)
			(end 0.12065 -0.305054)
			(stroke
				(width 0.1)
				(type default)
			)
			(layer "B.Fab")
		)
		(pad "1" smd circle
			(at 0.40005 0 90)
			(size 0 0)
			(layers "B.Cu" "B.Mask" "B.Paste")
			(net "IRQ_BMC_PCH_NMI_N")
		)
		(pad "2" smd circle
			(at -0.40005 0 90)
			(size 0 0)
			(layers "B.Cu" "B.Mask" "B.Paste")
			(net "IRQ_BMC_PCH_NMI_R_N")
		)
	)
	(footprint ""
		(layer "B.Cu")
		(at 12.319 -106.426 90)
		(property "Reference" "R134"
			(at 0 0 90)
			(layer "B.SilkS")
			(hide yes)
			(effects
				(font
					(size 1.27 1.27)
				)
				(justify mirror)
			)
		)
		(property "Value" ""
			(at 0 0 90)
			(layer "B.Fab")
			(effects
				(font
					(size 1.27 1.27)
				)
				(justify mirror)
			)
		)
		(duplicate_pad_numbers_are_jumpers no)
		(fp_line
			(start 0.7874 -0.4064)
			(end -0.7874 -0.4064)
			(stroke
				(width 0.1524)
				(type default)
			)
			(layer "B.SilkS")
		)
		(fp_line
			(start -0.7874 -0.4064)
			(end -0.7874 0.4064)
			(stroke
				(width 0.1524)
				(type default)
			)
			(layer "B.SilkS")
		)
		(fp_line
			(start 0.7874 0.4064)
			(end 0.7874 -0.4064)
			(stroke
				(width 0.1524)
				(type default)
			)
			(layer "B.SilkS")
		)
		(fp_line
			(start -0.7874 0.4064)
			(end 0.7874 0.4064)
			(stroke
				(width 0.1524)
				(type default)
			)
			(layer "B.SilkS")
		)
		(fp_line
			(start 0.67945 -0.305054)
			(end 0.12065 -0.305054)
			(stroke
				(width 0.1)
				(type default)
			)
			(layer "B.Fab")
		)
		(fp_line
			(start 0.12065 -0.305054)
			(end 0.12065 -0.2794)
			(stroke
				(width 0.1)
				(type default)
			)
			(layer "B.Fab")
		)
		(fp_line
			(start -0.12065 -0.3048)
			(end -0.67945 -0.3048)
			(stroke
				(width 0.1)
				(type default)
			)
			(layer "B.Fab")
		)
		(fp_line
			(start -0.67945 -0.3048)
			(end -0.67945 0.3048)
			(stroke
				(width 0.1)
				(type default)
			)
			(layer "B.Fab")
		)
		(fp_line
			(start 0.12065 -0.2794)
			(end -0.12065 -0.2794)
			(stroke
				(width 0.1)
				(type default)
			)
			(layer "B.Fab")
		)
		(fp_line
			(start -0.12065 -0.2794)
			(end -0.12065 -0.3048)
			(stroke
				(width 0.1)
				(type default)
			)
			(layer "B.Fab")
		)
		(fp_line
			(start 0.12065 0.2794)
			(end 0.12065 0.3048)
			(stroke
				(width 0.1)
				(type default)
			)
			(layer "B.Fab")
		)
		(fp_line
			(start -0.120396 0.2794)
			(end 0.12065 0.2794)
			(stroke
				(width 0.1)
				(type default)
			)
			(layer "B.Fab")
		)
		(fp_line
			(start 0.67945 0.3048)
			(end 0.67945 -0.305054)
			(stroke
				(width 0.1)
				(type default)
			)
			(layer "B.Fab")
		)
		(fp_line
			(start 0.12065 0.3048)
			(end 0.67945 0.3048)
			(stroke
				(width 0.1)
				(type default)
			)
			(layer "B.Fab")
		)
		(fp_line
			(start -0.120396 0.3048)
			(end -0.120396 0.2794)
			(stroke
				(width 0.1)
				(type default)
			)
			(layer "B.Fab")
		)
		(fp_line
			(start -0.67945 0.3048)
			(end -0.120396 0.3048)
			(stroke
				(width 0.1)
				(type default)
			)
			(layer "B.Fab")
		)
		(pad "1" smd circle
			(at 0.40005 0 270)
			(size 0 0)
			(layers "B.Cu" "B.Mask" "B.Paste")
			(net "FM_BMC_UARTSW_LSB_N")
		)
		(pad "2" smd circle
			(at -0.40005 0 270)
			(size 0 0)
			(layers "B.Cu" "B.Mask" "B.Paste")
			(net "FM_UARTSW_LSB_N")
		)
	)
)
